(kicad_pcb
	(version 20260206)
	(generator "pcbnew")
	(generator_version "10.0")
	(general
		(thickness 1.6)
		(legacy_teardrops no)
	)
	(paper "A4")
	(title_block
		(title "03242023_DA0F0TMBIJ0_F0T_Motherboard_J_brd_V01_OCP.brd")
		(comment 1 "Grand Teton / footprints 2802-2803 of 6105")
	)
	(layers
		(0 "F.Cu" signal "TOP")
		(4 "In1.Cu" signal "GND")
		(6 "In2.Cu" signal "IN1")
		(8 "In3.Cu" signal "GND1")
		(10 "In4.Cu" signal "IN2")
		(12 "In5.Cu" signal "GND2")
		(14 "In6.Cu" signal "IN3")
		(16 "In7.Cu" signal "GND3")
		(18 "In8.Cu" signal "VCC")
		(20 "In9.Cu" signal "VCC1")
		(22 "In10.Cu" signal "GND4")
		(24 "In11.Cu" signal "IN4")
		(26 "In12.Cu" signal "GND5")
		(28 "In13.Cu" signal "IN5")
		(30 "In14.Cu" signal "GND6")
		(32 "In15.Cu" signal "IN6")
		(34 "In16.Cu" signal "GND7")
		(2 "B.Cu" signal "BOTTOM")
		(9 "F.Adhes" user "F.Adhesive")
		(11 "B.Adhes" user "B.Adhesive")
		(13 "F.Paste" user "Package Geometry/Pastemask Top")
		(15 "B.Paste" user "Package Geometry/Pastemask Bottom")
		(5 "F.SilkS" user "Ref Des/Silkscreen Top")
		(7 "B.SilkS" user "Ref Des/Silkscreen Bottom")
		(1 "F.Mask" user "Board Geometry/Soldermask Top")
		(3 "B.Mask" user "Board Geometry/Soldermask Bottom")
		(17 "Dwgs.User" user "User.Drawings")
		(19 "Cmts.User" user "User.Comments")
		(21 "Eco1.User" user "User.Eco1")
		(23 "Eco2.User" user "User.Eco2")
		(25 "Edge.Cuts" user "Board Geometry/Outline")
		(27 "Margin" user)
		(31 "F.CrtYd" user "Package Geometry/Place Bound Top")
		(29 "B.CrtYd" user "Package Geometry/Place Bound Bottom")
		(35 "F.Fab" user "Ref Des/Assembly Top")
		(33 "B.Fab" user "Ref Des/Assembly Bottom")
	)
	(footprint ""
		(layer "F.Cu")
		(at 234.300014 -50.55997 180)
		(property "Reference" "J90"
			(at -0.596646 16.126968 0)
			(unlocked yes)
			(layer "F.SilkS")
			(effects
				(font
					(size 0.7874 0.5842)
					(thickness 0.1524)
				)
			)
		)
		(property "Value" ""
			(at 0 0 180)
			(layer "F.Fab")
			(effects
				(font
					(size 1.27 1.27)
				)
			)
		)
		(duplicate_pad_numbers_are_jumpers no)
		(fp_line
			(start 3.150108 12.115038)
			(end 1.529334 12.115038)
			(stroke
				(width 0.1524)
				(type default)
			)
			(layer "F.SilkS")
		)
		(fp_line
			(start 3.074924 12.014962)
			(end 1.632204 12.014962)
			(stroke
				(width 0.1524)
				(type default)
			)
			(layer "F.SilkS")
		)
		(fp_line
			(start 1.632204 -12.014962)
			(end 3.074924 -12.014962)
			(stroke
				(width 0.1524)
				(type default)
			)
			(layer "F.SilkS")
		)
		(fp_line
			(start 1.529334 -12.115038)
			(end 3.150108 -12.115038)
			(stroke
				(width 0.1524)
				(type default)
			)
			(layer "F.SilkS")
		)
		(fp_line
			(start -1.529334 12.115038)
			(end -3.150108 12.115038)
			(stroke
				(width 0.1524)
				(type default)
			)
			(layer "F.SilkS")
		)
		(fp_line
			(start -1.632204 12.014962)
			(end -3.074924 12.014962)
			(stroke
				(width 0.1524)
				(type default)
			)
			(layer "F.SilkS")
		)
		(fp_line
			(start -3.074924 -12.014962)
			(end -1.632204 -12.014962)
			(stroke
				(width 0.1524)
				(type default)
			)
			(layer "F.SilkS")
		)
		(fp_line
			(start -3.150108 -12.115038)
			(end -1.529334 -12.115038)
			(stroke
				(width 0.1524)
				(type default)
			)
			(layer "F.SilkS")
		)
		(fp_poly
			(pts
				(xy 3.901948 -10.042906) (xy 4.747006 -9.197848) (xy 3.479546 -8.775192)
			)
			(stroke
				(width 0)
				(type default)
			)
			(fill yes)
			(layer "F.SilkS")
		)
		(fp_line
			(start 3.074924 12.014962)
			(end -3.074924 12.014962)
			(stroke
				(width 0.1)
				(type default)
			)
			(layer "F.Fab")
		)
		(fp_line
			(start 3.074924 -12.014962)
			(end 3.074924 12.014962)
			(stroke
				(width 0.1)
				(type default)
			)
			(layer "F.Fab")
		)
		(fp_line
			(start -3.074924 12.014962)
			(end -3.074924 -12.014962)
			(stroke
				(width 0.1)
				(type default)
			)
			(layer "F.Fab")
		)
		(fp_line
			(start -3.074924 -12.014962)
			(end 3.074924 -12.014962)
			(stroke
				(width 0.1)
				(type default)
			)
			(layer "F.Fab")
		)
		(fp_poly
			(pts
				(xy 3.348736 -7.994904) (xy 4.543806 -8.592566) (xy 4.543806 -7.397496)
			)
			(stroke
				(width 0)
				(type default)
			)
			(fill yes)
			(layer "F.Fab")
		)
		(pad "" np_thru_hole circle
			(at -1.75006 -9.815068 90)
			(size 1.1176 1.1176)
			(drill 1.1176)
			(layers "*.Cu" "*.Mask")
			(clearance 0.381)
			(thermal_gap 0.381)
		)
		(pad "" np_thru_hole circle
			(at 0 9.815068 90)
			(size 1.1176 1.1176)
			(drill 1.1176)
			(layers "*.Cu" "*.Mask")
			(clearance 0.381)
			(thermal_gap 0.381)
		)
		(pad "A1" smd rect
			(at 2.29997 -7.994904 90)
			(size 0.381 1.27)
			(layers "F.Cu" "F.Mask" "F.Paste")
			(net "GND")
		)
		(pad "A2" smd rect
			(at 2.29997 -7.394956 90)
			(size 0.381 1.27)
			(layers "F.Cu" "F.Mask" "F.Paste")
			(net "GND")
		)
		(pad "A3" smd rect
			(at 2.29997 -6.795008 90)
			(size 0.381 1.27)
			(layers "F.Cu" "F.Mask" "F.Paste")
			(net "GND")
		)
		(pad "A4" smd rect
			(at 2.29997 -6.19506 90)
			(size 0.381 1.27)
			(layers "F.Cu" "F.Mask" "F.Paste")
			(net "GND")
		)
		(pad "A5" smd rect
			(at 2.29997 -5.595112 90)
			(size 0.381 1.27)
			(layers "F.Cu" "F.Mask" "F.Paste")
			(net "GND")
		)
		(pad "A6" smd rect
			(at 2.29997 -4.99491 90)
			(size 0.381 1.27)
			(layers "F.Cu" "F.Mask" "F.Paste")
			(net "GND")
		)
		(pad "A7" smd rect
			(at 2.29997 -4.394962 90)
			(size 0.381 1.27)
			(layers "F.Cu" "F.Mask" "F.Paste")
			(net "SMB_E1S_3V3AUX_ISO_SCL")
		)
		(pad "A8" smd rect
			(at 2.29997 -3.795014 90)
			(size 0.381 1.27)
			(layers "F.Cu" "F.Mask" "F.Paste")
			(net "SMB_E1S_3V3AUX_ISO_SDA")
		)
		(pad "A9" smd rect
			(at 2.29997 -3.195066 90)
			(size 0.381 1.27)
			(layers "F.Cu" "F.Mask" "F.Paste")
			(net "RST_SMB_E1S_0_N")
		)
		(pad "A10" smd rect
			(at 2.29997 -2.595118 90)
			(size 0.381 1.27)
			(layers "F.Cu" "F.Mask" "F.Paste")
			(net "E1S_0_LED_ACT_N")
		)
		(pad "A11" smd rect
			(at 2.29997 -1.994916 90)
			(size 0.381 1.27)
			(layers "F.Cu" "F.Mask" "F.Paste")
			(net "E1S_0_PERST1_CLKREQ_N")
		)
		(pad "A12" smd rect
			(at 2.29997 -1.394968 90)
			(size 0.381 1.27)
			(layers "F.Cu" "F.Mask" "F.Paste")
			(net "E1S_0_PRSNT_N")
		)
		(pad "A13" smd rect
			(at 2.29997 -0.79502 90)
			(size 0.381 1.27)
			(layers "F.Cu" "F.Mask" "F.Paste")
			(net "GND")
		)
		(pad "A14" smd rect
			(at 2.29997 -0.195072 90)
			(size 0.381 1.27)
			(layers "F.Cu" "F.Mask" "F.Paste")
			(net "TP_CLK_100M_E1S_0_DN")
		)
		(pad "A15" smd rect
			(at 2.29997 0.404876 90)
			(size 0.381 1.27)
			(layers "F.Cu" "F.Mask" "F.Paste")
			(net "TP_CLK_100M_E1S_0_DP")
		)
		(pad "A16" smd rect
			(at 2.29997 1.005078 90)
			(size 0.381 1.27)
			(layers "F.Cu" "F.Mask" "F.Paste")
			(net "GND")
		)
		(pad "A17" smd rect
			(at 2.29997 1.605026 90)
			(size 0.381 1.27)
			(layers "F.Cu" "F.Mask" "F.Paste")
			(net "P3E_PCH_E1S_RX_DP<0>")
		)
		(pad "A18" smd rect
			(at 2.29997 2.204974 90)
			(size 0.381 1.27)
			(layers "F.Cu" "F.Mask" "F.Paste")
			(net "P3E_PCH_E1S_RX_DN<0>")
		)
		(pad "A19" smd rect
			(at 2.29997 2.804922 90)
			(size 0.381 1.27)
			(layers "F.Cu" "F.Mask" "F.Paste")
			(net "GND")
		)
		(pad "A20" smd rect
			(at 2.29997 3.405124 90)
			(size 0.381 1.27)
			(layers "F.Cu" "F.Mask" "F.Paste")
			(net "P3E_PCH_E1S_RX_DN<1>")
		)
		(pad "A21" smd rect
			(at 2.29997 4.005072 90)
			(size 0.381 1.27)
			(layers "F.Cu" "F.Mask" "F.Paste")
			(net "P3E_PCH_E1S_RX_DP<1>")
		)
		(pad "A22" smd rect
			(at 2.29997 4.60502 90)
			(size 0.381 1.27)
			(layers "F.Cu" "F.Mask" "F.Paste")
			(net "GND")
		)
		(pad "A23" smd rect
			(at 2.29997 5.204968 90)
			(size 0.381 1.27)
			(layers "F.Cu" "F.Mask" "F.Paste")
			(net "P3E_PCH_E1S_RX_DN<2>")
		)
		(pad "A24" smd rect
			(at 2.29997 5.804916 90)
			(size 0.381 1.27)
			(layers "F.Cu" "F.Mask" "F.Paste")
			(net "P3E_PCH_E1S_RX_DP<2>")
		)
		(pad "A25" smd rect
			(at 2.29997 6.405118 90)
			(size 0.381 1.27)
			(layers "F.Cu" "F.Mask" "F.Paste")
			(net "GND")
		)
		(pad "A26" smd rect
			(at 2.29997 7.005066 90)
			(size 0.381 1.27)
			(layers "F.Cu" "F.Mask" "F.Paste")
			(net "P3E_PCH_E1S_RX_DN<3>")
		)
		(pad "A27" smd rect
			(at 2.29997 7.605014 90)
			(size 0.381 1.27)
			(layers "F.Cu" "F.Mask" "F.Paste")
			(net "P3E_PCH_E1S_RX_DP<3>")
		)
		(pad "A28" smd rect
			(at 2.29997 8.204962 90)
			(size 0.381 1.27)
			(layers "F.Cu" "F.Mask" "F.Paste")
			(net "GND")
		)
		(pad "B1" smd rect
			(at -2.29997 -7.994904 90)
			(size 0.381 1.27)
			(layers "F.Cu" "F.Mask" "F.Paste")
			(net "P12V_E1S_0")
		)
		(pad "B2" smd rect
			(at -2.29997 -7.394956 90)
			(size 0.381 1.27)
			(layers "F.Cu" "F.Mask" "F.Paste")
			(net "P12V_E1S_0")
		)
		(pad "B3" smd rect
			(at -2.29997 -6.795008 90)
			(size 0.381 1.27)
			(layers "F.Cu" "F.Mask" "F.Paste")
			(net "P12V_E1S_0")
		)
		(pad "B4" smd rect
			(at -2.29997 -6.19506 90)
			(size 0.381 1.27)
			(layers "F.Cu" "F.Mask" "F.Paste")
			(net "P12V_E1S_0")
		)
		(pad "B5" smd rect
			(at -2.29997 -5.595112 90)
			(size 0.381 1.27)
			(layers "F.Cu" "F.Mask" "F.Paste")
			(net "P12V_E1S_0")
		)
		(pad "B6" smd rect
			(at -2.29997 -4.99491 90)
			(size 0.381 1.27)
			(layers "F.Cu" "F.Mask" "F.Paste")
			(net "P12V_E1S_0")
		)
		(pad "B7" smd rect
			(at -2.29997 -4.394962 90)
			(size 0.381 1.27)
			(layers "F.Cu" "F.Mask" "F.Paste")
			(net "TP_E1S_0_MFG")
		)
		(pad "B8" smd rect
			(at -2.29997 -3.795014 90)
			(size 0.381 1.27)
			(layers "F.Cu" "F.Mask" "F.Paste")
			(net "TP_E1S_0_RFU")
		)
		(pad "B9" smd rect
			(at -2.29997 -3.195066 90)
			(size 0.381 1.27)
			(layers "F.Cu" "F.Mask" "F.Paste")
			(net "PU_E1S_0_DUALPORT_EN_N")
		)
		(pad "B10" smd rect
			(at -2.29997 -2.595118 90)
			(size 0.381 1.27)
			(layers "F.Cu" "F.Mask" "F.Paste")
			(net "RST_PCIE_PCH_E1S_PERST_N")
		)
		(pad "B11" smd rect
			(at -2.29997 -1.994916 90)
			(size 0.381 1.27)
			(layers "F.Cu" "F.Mask" "F.Paste")
			(net "P3V3_E1S_0")
		)
		(pad "B12" smd rect
			(at -2.29997 -1.394968 90)
			(size 0.381 1.27)
			(layers "F.Cu" "F.Mask" "F.Paste")
			(net "E1S_0_PWRDIS")
		)
		(pad "B13" smd rect
			(at -2.29997 -0.79502 90)
			(size 0.381 1.27)
			(layers "F.Cu" "F.Mask" "F.Paste")
			(net "GND")
		)
		(pad "B14" smd rect
			(at -2.29997 -0.195072 90)
			(size 0.381 1.27)
			(layers "F.Cu" "F.Mask" "F.Paste")
			(net "CLK_100M_E1S_0_DN")
		)
		(pad "B15" smd rect
			(at -2.29997 0.404876 90)
			(size 0.381 1.27)
			(layers "F.Cu" "F.Mask" "F.Paste")
			(net "CLK_100M_E1S_0_DP")
		)
		(pad "B16" smd rect
			(at -2.29997 1.005078 90)
			(size 0.381 1.27)
			(layers "F.Cu" "F.Mask" "F.Paste")
			(net "GND")
		)
		(pad "B17" smd rect
			(at -2.29997 1.605026 90)
			(size 0.381 1.27)
			(layers "F.Cu" "F.Mask" "F.Paste")
			(net "P3E_PCH_E1S_TX_C_DP<0>")
		)
		(pad "B18" smd rect
			(at -2.29997 2.204974 90)
			(size 0.381 1.27)
			(layers "F.Cu" "F.Mask" "F.Paste")
			(net "P3E_PCH_E1S_TX_C_DN<0>")
		)
		(pad "B19" smd rect
			(at -2.29997 2.804922 90)
			(size 0.381 1.27)
			(layers "F.Cu" "F.Mask" "F.Paste")
			(net "GND")
		)
		(pad "B20" smd rect
			(at -2.29997 3.405124 90)
			(size 0.381 1.27)
			(layers "F.Cu" "F.Mask" "F.Paste")
			(net "P3E_PCH_E1S_TX_C_DP<1>")
		)
		(pad "B21" smd rect
			(at -2.29997 4.005072 90)
			(size 0.381 1.27)
			(layers "F.Cu" "F.Mask" "F.Paste")
			(net "P3E_PCH_E1S_TX_C_DN<1>")
		)
		(pad "B22" smd rect
			(at -2.29997 4.60502 90)
			(size 0.381 1.27)
			(layers "F.Cu" "F.Mask" "F.Paste")
			(net "GND")
		)
		(pad "B23" smd rect
			(at -2.29997 5.204968 90)
			(size 0.381 1.27)
			(layers "F.Cu" "F.Mask" "F.Paste")
			(net "P3E_PCH_E1S_TX_C_DN<2>")
		)
		(pad "B24" smd rect
			(at -2.29997 5.804916 90)
			(size 0.381 1.27)
			(layers "F.Cu" "F.Mask" "F.Paste")
			(net "P3E_PCH_E1S_TX_C_DP<2>")
		)
		(pad "B25" smd rect
			(at -2.29997 6.405118 90)
			(size 0.381 1.27)
			(layers "F.Cu" "F.Mask" "F.Paste")
			(net "GND")
		)
		(pad "B26" smd rect
			(at -2.29997 7.005066 90)
			(size 0.381 1.27)
			(layers "F.Cu" "F.Mask" "F.Paste")
			(net "P3E_PCH_E1S_TX_C_DN<3>")
		)
		(pad "B27" smd rect
			(at -2.29997 7.605014 90)
			(size 0.381 1.27)
			(layers "F.Cu" "F.Mask" "F.Paste")
			(net "P3E_PCH_E1S_TX_C_DP<3>")
		)
		(pad "B28" smd rect
			(at -2.29997 8.204962 90)
			(size 0.381 1.27)
			(layers "F.Cu" "F.Mask" "F.Paste")
			(net "GND")
		)
		(pad "G1" thru_hole oval
			(at 0 -11.364976 90)
			(size 1.6256 3.4798)
			(drill oval 1.1176 2.4638)
			(layers "*.Cu" "*.Mask")
			(remove_unused_layers no)
			(net "GND")
			(clearance 0.127)
			(thermal_gap 0.127)
		)
		(pad "G2" thru_hole oval
			(at 0 11.364976 90)
			(size 1.6256 3.4798)
			(drill oval 1.1176 2.4638)
			(layers "*.Cu" "*.Mask")
			(remove_unused_layers no)
			(net "GND")
			(clearance 0.127)
			(thermal_gap 0.127)
		)
		(zone
			(layer "F.Cu")
			(hatch none 0.5)
			(connect_pads
				(clearance 0)
			)
			(min_thickness 0.25)
			(keepout
				(tracks not_allowed)
				(vias allowed)
				(pads allowed)
				(copperpour not_allowed)
				(footprints allowed)
			)
			(placement
				(enabled no)
				(sheetname "")
			)
			(fill
				(thermal_gap 0.5)
				(thermal_bridge_width 0.5)
				(island_removal_mode 0)
			)
			(polygon
				(pts
					(xy 235.679996 -62.62497) (xy 232.929938 -62.62497) (xy 232.929938 -59.675014) (xy 235.679996 -59.675014)
				)
			)
		)
		(zone
			(layer "F.Cu")
			(hatch none 0.5)
			(connect_pads
				(clearance 0)
			)
			(min_thickness 0.25)
			(keepout
				(tracks not_allowed)
				(vias allowed)
				(pads allowed)
				(copperpour not_allowed)
				(footprints allowed)
			)
			(placement
				(enabled no)
				(sheetname "")
			)
			(fill
				(thermal_gap 0.5)
				(thermal_bridge_width 0.5)
				(island_removal_mode 0)
			)
			(polygon
				(pts
					(xy 236.750098 -41.444926) (xy 232.920032 -41.444926) (xy 232.920032 -38.49497) (xy 236.750098 -38.49497)
				)
			)
		)
		(zone
			(layers "F.Cu" "B.Cu" "In1.Cu" "In2.Cu" "In3.Cu" "In4.Cu" "In5.Cu" "In6.Cu"
				"In7.Cu" "In8.Cu" "In9.Cu" "In10.Cu" "In11.Cu" "In12.Cu" "In13.Cu" "In14.Cu"
				"In15.Cu" "In16.Cu"
			)
			(hatch none 0.5)
			(connect_pads
				(clearance 0)
			)
			(min_thickness 0.25)
			(keepout
				(tracks not_allowed)
				(vias allowed)
				(pads allowed)
				(copperpour not_allowed)
				(footprints allowed)
			)
			(placement
				(enabled no)
				(sheetname "")
			)
			(fill
				(thermal_gap 0.5)
				(thermal_bridge_width 0.5)
				(island_removal_mode 0)
			)
			(polygon
				(pts
					(arc
						(start 235.265214 -60.375038)
						(mid 233.334814 -60.375038)
						(end 235.265214 -60.375038)
					)
				)
			)
		)
		(zone
			(layers "F.Cu" "B.Cu" "In1.Cu" "In2.Cu" "In3.Cu" "In4.Cu" "In5.Cu" "In6.Cu"
				"In7.Cu" "In8.Cu" "In9.Cu" "In10.Cu" "In11.Cu" "In12.Cu" "In13.Cu" "In14.Cu"
				"In15.Cu" "In16.Cu"
			)
			(hatch none 0.5)
			(connect_pads
				(clearance 0)
			)
			(min_thickness 0.25)
			(keepout
				(tracks not_allowed)
				(vias allowed)
				(pads allowed)
				(copperpour not_allowed)
				(footprints allowed)
			)
			(placement
				(enabled no)
				(sheetname "")
			)
			(fill
				(thermal_gap 0.5)
				(thermal_bridge_width 0.5)
				(island_removal_mode 0)
			)
			(polygon
				(pts
					(arc
						(start 237.015274 -40.744902)
						(mid 235.084874 -40.744902)
						(end 237.015274 -40.744902)
					)
				)
			)
		)
	)
	(footprint ""
		(layer "F.Cu")
		(at 122.05208 -106.238548 -90)
		(property "Reference" "R4046"
			(at 0 0 270)
			(layer "F.SilkS")
			(hide yes)
			(effects
				(font
					(size 1.27 1.27)
				)
			)
		)
		(property "Value" ""
			(at 0 0 270)
			(layer "F.Fab")
			(effects
				(font
					(size 1.27 1.27)
				)
			)
		)
		(duplicate_pad_numbers_are_jumpers no)
		(fp_line
			(start -0.7874 0.4064)
			(end -0.7874 -0.4064)
			(stroke
				(width 0.1524)
				(type default)
			)
			(layer "F.SilkS")
		)
		(fp_line
			(start 0.7874 0.4064)
			(end -0.7874 0.4064)
			(stroke
				(width 0.1524)
				(type default)
			)
			(layer "F.SilkS")
		)
		(fp_line
			(start -0.7874 -0.4064)
			(end 0.7874 -0.4064)
			(stroke
				(width 0.1524)
				(type default)
			)
			(layer "F.SilkS")
		)
		(fp_line
			(start 0.7874 -0.4064)
			(end 0.7874 0.4064)
			(stroke
				(width 0.1524)
				(type default)
			)
			(layer "F.SilkS")
		)
		(fp_line
			(start -0.67945 0.3048)
			(end -0.67945 -0.305054)
			(stroke
				(width 0.1)
				(type default)
			)
			(layer "F.Fab")
		)
		(fp_line
			(start -0.12065 0.3048)
			(end -0.67945 0.3048)
			(stroke
				(width 0.1)
				(type default)
			)
			(layer "F.Fab")
		)
		(fp_line
			(start 0.120396 0.3048)
			(end 0.120396 0.2794)
			(stroke
				(width 0.1)
				(type default)
			)
			(layer "F.Fab")
		)
		(fp_line
			(start 0.67945 0.3048)
			(end 0.120396 0.3048)
			(stroke
				(width 0.1)
				(type default)
			)
			(layer "F.Fab")
		)
		(fp_line
			(start -0.12065 0.2794)
			(end -0.12065 0.3048)
			(stroke
				(width 0.1)
				(type default)
			)
			(layer "F.Fab")
		)
		(fp_line
			(start 0.120396 0.2794)
			(end -0.12065 0.2794)
			(stroke
				(width 0.1)
				(type default)
			)
			(layer "F.Fab")
		)
		(fp_line
			(start -0.12065 -0.2794)
			(end 0.12065 -0.2794)
			(stroke
				(width 0.1)
				(type default)
			)
			(layer "F.Fab")
		)
		(fp_line
			(start 0.12065 -0.2794)
			(end 0.12065 -0.3048)
			(stroke
				(width 0.1)
				(type default)
			)
			(layer "F.Fab")
		)
		(fp_line
			(start 0.12065 -0.3048)
			(end 0.67945 -0.3048)
			(stroke
				(width 0.1)
				(type default)
			)
			(layer "F.Fab")
		)
		(fp_line
			(start 0.67945 -0.3048)
			(end 0.67945 0.3048)
			(stroke
				(width 0.1)
				(type default)
			)
			(layer "F.Fab")
		)
		(fp_line
			(start -0.67945 -0.305054)
			(end -0.12065 -0.305054)
			(stroke
				(width 0.1)
				(type default)
			)
			(layer "F.Fab")
		)
		(fp_line
			(start -0.12065 -0.305054)
			(end -0.12065 -0.2794)
			(stroke
				(width 0.1)
				(type default)
			)
			(layer "F.Fab")
		)
		(pad "1" smd circle
			(at -0.40005 0 270)
			(size 0 0)
			(layers "F.Cu" "F.Mask" "F.Paste")
			(net "RST_CPU1_DRAM_AB_PLD_LVT3_R_N")
		)
		(pad "2" smd circle
			(at 0.40005 0 270)
			(size 0 0)
			(layers "F.Cu" "F.Mask" "F.Paste")
			(net "RST_CPU1_DRAM_AB_PLD_LVT3_N")
		)
	)
)
